(kicad_pcb
	(version 20241229)
	(generator "pcbnew")
	(generator_version "9.0")
	(general
		(thickness 1.552)
		(legacy_teardrops no)
	)
	(paper "A4")
	(title_block
		(date "2023-07-25")
		(rev "1.1.4")
		(comment 9 "footprints 38-43 of 379")
	)
	(layers
		(0 "F.Cu" signal)
		(4 "In1.Cu" signal)
		(6 "In2.Cu" signal)
		(8 "In3.Cu" signal)
		(10 "In4.Cu" signal)
		(12 "In5.Cu" signal)
		(14 "In6.Cu" signal)
		(2 "B.Cu" signal)
		(9 "F.Adhes" user "F.Adhesive")
		(11 "B.Adhes" user "B.Adhesive")
		(13 "F.Paste" user)
		(15 "B.Paste" user)
		(5 "F.SilkS" user "F.Silkscreen")
		(7 "B.SilkS" user "B.Silkscreen")
		(1 "F.Mask" user)
		(3 "B.Mask" user)
		(17 "Dwgs.User" user "User.Drawings")
		(19 "Cmts.User" user "User.Comments")
		(21 "Eco1.User" user "User.Eco1")
		(23 "Eco2.User" user "User.Eco2")
		(25 "Edge.Cuts" user)
		(27 "Margin" user)
		(31 "F.CrtYd" user "F.Courtyard")
		(29 "B.CrtYd" user "B.Courtyard")
		(35 "F.Fab" user)
		(33 "B.Fab" user)
	)
	(footprint "antmicro-footprints:C_0402_1005Metric"
		(layer "F.Cu")
		(at 87.6 79.4 180)
		(descr "Capacitor SMD 0402")
		(tags "capacitor SMD 0402")
		(property "Reference" "C56"
			(at 0.67 6.16 0)
			(layer "F.SilkS")
			(effects
				(font
					(size 0.65 0.65)
					(thickness 0.15)
				)
				(justify right bottom)
			)
		)
		(property "Value" "C_470n_0402"
			(at 0 1.4 0)
			(layer "F.Fab")
			(hide yes)
			(effects
				(font
					(size 0.7 0.7)
					(thickness 0.15)
				)
				(justify right bottom)
			)
		)
		(property "Datasheet" "https://product.tdk.com/en/search/capacitor/ceramic/mlcc/info?part_no=C1005X5R1E474M050BB"
			(at 0 0 180)
			(layer "F.Fab")
			(hide yes)
			(effects
				(font
					(size 1.27 1.27)
					(thickness 0.15)
				)
			)
		)
		(property "Description" "SMD Multilayer Ceramic Capacitor, 0.47 µF, 25 V, 0402 [1005 Metric], ± 20%, X5R, C"
			(at 0 0 180)
			(layer "F.Fab")
			(hide yes)
			(effects
				(font
					(size 1.27 1.27)
					(thickness 0.15)
				)
			)
		)
		(property "Author" "Antmicro"
			(at 175.2 158.8 0)
			(layer "F.Fab")
			(hide yes)
			(effects
				(font
					(size 1 1)
					(thickness 0.15)
				)
			)
		)
		(property "Dielectric" ""
			(at 175.2 158.8 0)
			(layer "F.Fab")
			(hide yes)
			(effects
				(font
					(size 1 1)
					(thickness 0.15)
				)
			)
		)
		(property "License" "Apache-2.0"
			(at 175.2 158.8 0)
			(layer "F.Fab")
			(hide yes)
			(effects
				(font
					(size 1 1)
					(thickness 0.15)
				)
			)
		)
		(property "MPN" "C1005X5R1E474M050BB"
			(at 175.2 158.8 0)
			(layer "F.Fab")
			(hide yes)
			(effects
				(font
					(size 1 1)
					(thickness 0.15)
				)
			)
		)
		(property "Manufacturer" "TDK"
			(at 175.2 158.8 0)
			(layer "F.Fab")
			(hide yes)
			(effects
				(font
					(size 1 1)
					(thickness 0.15)
				)
			)
		)
		(property "Val" "470n"
			(at 175.2 158.8 0)
			(layer "F.Fab")
			(hide yes)
			(effects
				(font
					(size 1 1)
					(thickness 0.15)
				)
			)
		)
		(property "Voltage" ""
			(at 175.2 158.8 0)
			(layer "F.Fab")
			(hide yes)
			(effects
				(font
					(size 1 1)
					(thickness 0.15)
				)
			)
		)
		(sheetname "/SDI/")
		(sheetfile "sdi.kicad_sch")
		(attr smd)
		(fp_rect
			(start -0.925 -0.47)
			(end 0.925 0.47)
			(stroke
				(width 0.05)
				(type default)
			)
			(fill no)
			(layer "F.CrtYd")
		)
		(fp_line
			(start 0.504 0.248)
			(end -0.494 0.248)
			(stroke
				(width 0.15)
				(type solid)
			)
			(layer "F.Fab")
		)
		(fp_line
			(start 0.504 -0.25)
			(end 0.504 0.248)
			(stroke
				(width 0.15)
				(type solid)
			)
			(layer "F.Fab")
		)
		(fp_line
			(start -0.494 0.248)
			(end -0.494 -0.25)
			(stroke
				(width 0.15)
				(type solid)
			)
			(layer "F.Fab")
		)
		(fp_line
			(start -0.494 -0.25)
			(end 0.504 -0.25)
			(stroke
				(width 0.15)
				(type solid)
			)
			(layer "F.Fab")
		)
		(fp_text user "License: Apache-2.0"
			(at -0.939 5.799 180)
			(layer "F.Fab")
			(effects
				(font
					(size 0.7 0.7)
					(thickness 0.15)
				)
				(justify left bottom)
			)
		)
		(fp_text user "Author: Antmicro"
			(at -0.939 3.399 180)
			(layer "F.Fab")
			(effects
				(font
					(size 0.7 0.7)
					(thickness 0.15)
				)
				(justify left bottom)
			)
		)
		(fp_text user "${REFERENCE}"
			(at -0.939 4.599 180)
			(layer "F.Fab")
			(effects
				(font
					(size 0.7 0.7)
					(thickness 0.15)
				)
				(justify left bottom)
			)
		)
		(pad "1" smd roundrect
			(at -0.48 0 180)
			(size 0.59 0.64)
			(layers "F.Cu" "F.Mask" "F.Paste")
			(roundrect_rratio 0.25)
			(net 291 "/SDI/AGC_N")
			(pintype "passive")
		)
		(pad "2" smd roundrect
			(at 0.48 0 180)
			(size 0.59 0.64)
			(layers "F.Cu" "F.Mask" "F.Paste")
			(roundrect_rratio 0.25)
			(net 1 "GND")
			(pintype "passive")
		)
	)
	(footprint "antmicro-footprints:R_0402_1005Metric"
		(layer "F.Cu")
		(at 88 77.9 -90)
		(descr "Resistor SMD 0402")
		(tags "resistor SMD 0402")
		(property "Reference" "R53"
			(at -7.66 1.17 90)
			(layer "F.SilkS")
			(effects
				(font
					(size 0.65 0.65)
					(thickness 0.15)
				)
				(justify right bottom)
			)
		)
		(property "Value" "R_37R4_0402"
			(at 0 1.4 90)
			(layer "F.Fab")
			(hide yes)
			(effects
				(font
					(size 0.7 0.7)
					(thickness 0.15)
				)
				(justify right bottom)
			)
		)
		(property "Datasheet" "https://www.bourns.com/docs/product-datasheets/cr.pdf"
			(at 0 0 270)
			(layer "F.Fab")
			(hide yes)
			(effects
				(font
					(size 1.27 1.27)
					(thickness 0.15)
				)
			)
		)
		(property "Description" "SMD Chip Resistor, 37.4 ohm, ± 1%, 100 mW, 0402 [1005 Metric], Thick Film, Precision"
			(at 0 0 270)
			(layer "F.Fab")
			(hide yes)
			(effects
				(font
					(size 1.27 1.27)
					(thickness 0.15)
				)
			)
		)
		(property "Author" "Antmicro"
			(at 10.1 165.9 0)
			(layer "F.Fab")
			(hide yes)
			(effects
				(font
					(size 1 1)
					(thickness 0.15)
				)
			)
		)
		(property "License" "Apache-2.0"
			(at 10.1 165.9 0)
			(layer "F.Fab")
			(hide yes)
			(effects
				(font
					(size 1 1)
					(thickness 0.15)
				)
			)
		)
		(property "MPN" "CR0402-FX-37R4GLF"
			(at 10.1 165.9 0)
			(layer "F.Fab")
			(hide yes)
			(effects
				(font
					(size 1 1)
					(thickness 0.15)
				)
			)
		)
		(property "Manufacturer" "Bourns"
			(at 10.1 165.9 0)
			(layer "F.Fab")
			(hide yes)
			(effects
				(font
					(size 1 1)
					(thickness 0.15)
				)
			)
		)
		(property "Tolerance" "1%"
			(at 10.1 165.9 0)
			(layer "F.Fab")
			(hide yes)
			(effects
				(font
					(size 1 1)
					(thickness 0.15)
				)
			)
		)
		(property "Val" "37R4"
			(at 10.1 165.9 0)
			(layer "F.Fab")
			(hide yes)
			(effects
				(font
					(size 1 1)
					(thickness 0.15)
				)
			)
		)
		(sheetname "/SDI/")
		(sheetfile "sdi.kicad_sch")
		(attr smd)
		(fp_rect
			(start -0.925 -0.47)
			(end 0.925 0.47)
			(stroke
				(width 0.05)
				(type default)
			)
			(fill no)
			(layer "F.CrtYd")
		)
		(fp_rect
			(start -0.5 -0.25)
			(end 0.5 0.25)
			(stroke
				(width 0.15)
				(type solid)
			)
			(fill no)
			(layer "F.Fab")
		)
		(fp_text user "License: Apache-2.0"
			(at -0.95 5.169 270)
			(layer "F.Fab")
			(effects
				(font
					(size 0.7 0.7)
					(thickness 0.15)
				)
				(justify left bottom)
			)
		)
		(fp_text user "Author: Antmicro"
			(at -0.95 4.169 270)
			(layer "F.Fab")
			(effects
				(font
					(size 0.7 0.7)
					(thickness 0.15)
				)
				(justify left bottom)
			)
		)
		(fp_text user "${REFERENCE}"
			(at -0.95 3.168 270)
			(layer "F.Fab")
			(effects
				(font
					(size 0.7 0.7)
					(thickness 0.15)
				)
				(justify left bottom)
			)
		)
		(pad "1" smd roundrect
			(at -0.48 0 270)
			(size 0.59 0.64)
			(layers "F.Cu" "F.Mask" "F.Paste")
			(roundrect_rratio 0.25)
			(net 293 "/SDI/SDI_N2")
			(pintype "passive")
		)
		(pad "2" smd roundrect
			(at 0.48 0 270)
			(size 0.59 0.64)
			(layers "F.Cu" "F.Mask" "F.Paste")
			(roundrect_rratio 0.25)
			(net 1 "GND")
			(pintype "passive")
		)
	)
	(footprint "antmicro-footprints:R_0402_1005Metric"
		(layer "F.Cu")
		(at 91.8 69.2 -90)
		(descr "Resistor SMD 0402")
		(tags "resistor SMD 0402")
		(property "Reference" "R54"
			(at -1.31 -0.48 270)
			(layer "F.SilkS")
			(effects
				(font
					(size 0.65 0.65)
					(thickness 0.15)
				)
				(justify left bottom)
			)
		)
		(property "Value" "R_100k_0402"
			(at 0 1.4 270)
			(layer "F.Fab")
			(hide yes)
			(effects
				(font
					(size 0.7 0.7)
					(thickness 0.15)
				)
				(justify left bottom)
			)
		)
		(property "Datasheet" "https://www.bourns.com/docs/product-datasheets/cr.pdf"
			(at 0 0 270)
			(layer "F.Fab")
			(hide yes)
			(effects
				(font
					(size 1.27 1.27)
					(thickness 0.15)
				)
			)
		)
		(property "Description" "SMD Chip Resistor, 100 kohm, ± 1%, 62.5 mW, 0402 [1005 Metric], Thick Film, General Purpose"
			(at 0 0 270)
			(layer "F.Fab")
			(hide yes)
			(effects
				(font
					(size 1.27 1.27)
					(thickness 0.15)
				)
			)
		)
		(property "Author" "Antmicro"
			(at 22.6 161 0)
			(layer "F.Fab")
			(hide yes)
			(effects
				(font
					(size 1 1)
					(thickness 0.15)
				)
			)
		)
		(property "License" "Apache-2.0"
			(at 22.6 161 0)
			(layer "F.Fab")
			(hide yes)
			(effects
				(font
					(size 1 1)
					(thickness 0.15)
				)
			)
		)
		(property "MPN" "CR0402-FX-1003GLF"
			(at 22.6 161 0)
			(layer "F.Fab")
			(hide yes)
			(effects
				(font
					(size 1 1)
					(thickness 0.15)
				)
			)
		)
		(property "Manufacturer" "Bourns"
			(at 22.6 161 0)
			(layer "F.Fab")
			(hide yes)
			(effects
				(font
					(size 1 1)
					(thickness 0.15)
				)
			)
		)
		(property "Tolerance" "1%"
			(at 22.6 161 0)
			(layer "F.Fab")
			(hide yes)
			(effects
				(font
					(size 1 1)
					(thickness 0.15)
				)
			)
		)
		(property "Val" "100k"
			(at 22.6 161 0)
			(layer "F.Fab")
			(hide yes)
			(effects
				(font
					(size 1 1)
					(thickness 0.15)
				)
			)
		)
		(sheetname "/SDI/")
		(sheetfile "sdi.kicad_sch")
		(attr smd)
		(fp_rect
			(start -0.925 -0.47)
			(end 0.925 0.47)
			(stroke
				(width 0.05)
				(type default)
			)
			(fill no)
			(layer "F.CrtYd")
		)
		(fp_rect
			(start -0.5 -0.25)
			(end 0.5 0.25)
			(stroke
				(width 0.15)
				(type solid)
			)
			(fill no)
			(layer "F.Fab")
		)
		(fp_text user "License: Apache-2.0"
			(at -0.95 5.169 270)
			(layer "F.Fab")
			(effects
				(font
					(size 0.7 0.7)
					(thickness 0.15)
				)
				(justify left bottom)
			)
		)
		(fp_text user "${REFERENCE}"
			(at -0.95 3.168 270)
			(layer "F.Fab")
			(effects
				(font
					(size 0.7 0.7)
					(thickness 0.15)
				)
				(justify left bottom)
			)
		)
		(fp_text user "Author: Antmicro"
			(at -0.95 4.169 270)
			(layer "F.Fab")
			(effects
				(font
					(size 0.7 0.7)
					(thickness 0.15)
				)
				(justify left bottom)
			)
		)
		(pad "1" smd roundrect
			(at -0.48 0 270)
			(size 0.59 0.64)
			(layers "F.Cu" "F.Mask" "F.Paste")
			(roundrect_rratio 0.25)
			(net 1 "GND")
			(pintype "passive")
		)
		(pad "2" smd roundrect
			(at 0.48 0 270)
			(size 0.59 0.64)
			(layers "F.Cu" "F.Mask" "F.Paste")
			(roundrect_rratio 0.25)
			(net 288 "Net-(U15B-LB_CONT)")
			(pintype "passive")
		)
	)
	(footprint "antmicro-footprints:C_0402_1005Metric"
		(layer "F.Cu")
		(at 159.925 88.3 -90)
		(descr "Capacitor SMD 0402")
		(tags "capacitor SMD 0402")
		(property "Reference" "C109"
			(at -3.76 -0.405 90)
			(layer "F.SilkS")
			(effects
				(font
					(size 0.65 0.65)
					(thickness 0.15)
				)
				(justify right bottom)
			)
		)
		(property "Value" "C_100n_0402"
			(at 0 1.4 90)
			(layer "F.Fab")
			(hide yes)
			(effects
				(font
					(size 0.7 0.7)
					(thickness 0.15)
				)
				(justify right bottom)
			)
		)
		(property "Datasheet" "https://www.murata.com/products/productdetail?partno=GRM155R61H104KE14%23"
			(at 0 0 270)
			(layer "F.Fab")
			(hide yes)
			(effects
				(font
					(size 1.27 1.27)
					(thickness 0.15)
				)
			)
		)
		(property "Description" "SMD Multilayer Ceramic Capacitor, 0.1 µF, 50 V, 0402 [1005 Metric], ± 10%, X5R, GRM Series"
			(at 0 0 270)
			(layer "F.Fab")
			(hide yes)
			(effects
				(font
					(size 1.27 1.27)
					(thickness 0.15)
				)
			)
		)
		(property "Author" "Antmicro"
			(at 71.625 248.225 0)
			(layer "F.Fab")
			(hide yes)
			(effects
				(font
					(size 1 1)
					(thickness 0.15)
				)
			)
		)
		(property "Dielectric" "X5R"
			(at 71.625 248.225 0)
			(layer "F.Fab")
			(hide yes)
			(effects
				(font
					(size 1 1)
					(thickness 0.15)
				)
			)
		)
		(property "License" "Apache-2.0"
			(at 71.625 248.225 0)
			(layer "F.Fab")
			(hide yes)
			(effects
				(font
					(size 1 1)
					(thickness 0.15)
				)
			)
		)
		(property "MPN" "GRM155R61H104KE14D"
			(at 71.625 248.225 0)
			(layer "F.Fab")
			(hide yes)
			(effects
				(font
					(size 1 1)
					(thickness 0.15)
				)
			)
		)
		(property "Manufacturer" "Murata"
			(at 71.625 248.225 0)
			(layer "F.Fab")
			(hide yes)
			(effects
				(font
					(size 1 1)
					(thickness 0.15)
				)
			)
		)
		(property "Val" "100n"
			(at 71.625 248.225 0)
			(layer "F.Fab")
			(hide yes)
			(effects
				(font
					(size 1 1)
					(thickness 0.15)
				)
			)
		)
		(property "Voltage" "50V"
			(at 71.625 248.225 0)
			(layer "F.Fab")
			(hide yes)
			(effects
				(font
					(size 1 1)
					(thickness 0.15)
				)
			)
		)
		(sheetname "/Peripherals/")
		(sheetfile "peripherals.kicad_sch")
		(attr smd)
		(fp_rect
			(start -0.925 -0.47)
			(end 0.925 0.47)
			(stroke
				(width 0.05)
				(type default)
			)
			(fill no)
			(layer "F.CrtYd")
		)
		(fp_line
			(start -0.494 0.248)
			(end -0.494 -0.25)
			(stroke
				(width 0.15)
				(type solid)
			)
			(layer "F.Fab")
		)
		(fp_line
			(start 0.504 0.248)
			(end -0.494 0.248)
			(stroke
				(width 0.15)
				(type solid)
			)
			(layer "F.Fab")
		)
		(fp_line
			(start -0.494 -0.25)
			(end 0.504 -0.25)
			(stroke
				(width 0.15)
				(type solid)
			)
			(layer "F.Fab")
		)
		(fp_line
			(start 0.504 -0.25)
			(end 0.504 0.248)
			(stroke
				(width 0.15)
				(type solid)
			)
			(layer "F.Fab")
		)
		(fp_text user "${REFERENCE}"
			(at -0.939 4.599 270)
			(layer "F.Fab")
			(effects
				(font
					(size 0.7 0.7)
					(thickness 0.15)
				)
				(justify left bottom)
			)
		)
		(fp_text user "License: Apache-2.0"
			(at -0.939 5.799 270)
			(layer "F.Fab")
			(effects
				(font
					(size 0.7 0.7)
					(thickness 0.15)
				)
				(justify left bottom)
			)
		)
		(fp_text user "Author: Antmicro"
			(at -0.939 3.399 270)
			(layer "F.Fab")
			(effects
				(font
					(size 0.7 0.7)
					(thickness 0.15)
				)
				(justify left bottom)
			)
		)
		(pad "1" smd roundrect
			(at -0.48 0 270)
			(size 0.59 0.64)
			(layers "F.Cu" "F.Mask" "F.Paste")
			(roundrect_rratio 0.25)
			(net 1 "GND")
			(pintype "passive")
		)
		(pad "2" smd roundrect
			(at 0.48 0 270)
			(size 0.59 0.64)
			(layers "F.Cu" "F.Mask" "F.Paste")
			(roundrect_rratio 0.25)
			(net 2 "+3V3")
			(pintype "passive")
		)
	)
	(footprint "antmicro-footprints:TP_SMD_0.75mm"
		(layer "F.Cu")
		(at 109.09 91.3 -90)
		(property "Reference" "TP21"
			(at -0.16 -1.24 270)
			(layer "F.SilkS")
			(effects
				(font
					(size 0.65 0.65)
					(thickness 0.15)
				)
				(justify left bottom)
			)
		)
		(property "Value" "TP_0.75mm_SMD"
			(at 0 1.2 90)
			(layer "F.Fab")
			(hide yes)
			(effects
				(font
					(size 0.7 0.7)
					(thickness 0.15)
				)
				(justify right bottom)
			)
		)
		(property "Description" "SMT test point"
			(at 0 0 270)
			(layer "F.Fab")
			(hide yes)
			(effects
				(font
					(size 1.27 1.27)
					(thickness 0.15)
				)
			)
		)
		(property "Author" "Antmicro"
			(at 17.79 200.39 0)
			(layer "F.Fab")
			(hide yes)
			(effects
				(font
					(size 1 1)
					(thickness 0.15)
				)
			)
		)
		(property "License" "Apache-2.0"
			(at 17.79 200.39 0)
			(layer "F.Fab")
			(hide yes)
			(effects
				(font
					(size 1 1)
					(thickness 0.15)
				)
			)
		)
		(property "MPN" ""
			(at 17.79 200.39 0)
			(layer "F.Fab")
			(hide yes)
			(effects
				(font
					(size 1 1)
					(thickness 0.15)
				)
			)
		)
		(property "Manufacturer" ""
			(at 17.79 200.39 0)
			(layer "F.Fab")
			(hide yes)
			(effects
				(font
					(size 1 1)
					(thickness 0.15)
				)
			)
		)
		(sheetname "/FPGA/")
		(sheetfile "fpga.kicad_sch")
		(attr exclude_from_pos_files)
		(fp_circle
			(center 0 0)
			(end 0.475 0)
			(stroke
				(width 0.05)
				(type default)
			)
			(fill no)
			(layer "F.CrtYd")
		)
		(fp_text user "License: Apache-2.0"
			(at -0.4 5.101 270)
			(layer "F.Fab")
			(effects
				(font
					(size 0.7 0.7)
					(thickness 0.15)
				)
				(justify left bottom)
			)
		)
		(fp_text user "${REFERENCE}"
			(at -0.4 2.7 270)
			(layer "F.Fab")
			(effects
				(font
					(size 0.7 0.7)
					(thickness 0.15)
				)
				(justify left bottom)
			)
		)
		(fp_text user "Author: Antmicro"
			(at -0.4 3.901 270)
			(layer "F.Fab")
			(effects
				(font
					(size 0.7 0.7)
					(thickness 0.15)
				)
				(justify left bottom)
			)
		)
		(pad "1" smd circle
			(at 0 0 270)
			(size 0.75 0.75)
			(layers "F.Cu" "F.Mask")
			(net 324 "Net-(U21-D4)")
			(pinfunction "1")
			(pintype "passive")
		)
	)
	(footprint "antmicro-footprints:TP_SMD_0.75mm"
		(layer "F.Cu")
		(at 167.09 66.1 -90)
		(property "Reference" "TP12"
			(at 0.44 -0.64 0)
			(layer "F.SilkS")
			(effects
				(font
					(size 0.65 0.65)
					(thickness 0.15)
				)
				(justify left bottom)
			)
		)
		(property "Value" "TP_0.75mm_SMD"
			(at 0 1.2 270)
			(layer "F.Fab")
			(hide yes)
			(effects
				(font
					(size 0.7 0.7)
					(thickness 0.15)
				)
				(justify left bottom)
			)
		)
		(property "Description" "SMT test point"
			(at 0 0 270)
			(layer "F.Fab")
			(hide yes)
			(effects
				(font
					(size 1.27 1.27)
					(thickness 0.15)
				)
			)
		)
		(property "Author" "Antmicro"
			(at 100.99 233.19 0)
			(layer "F.Fab")
			(hide yes)
			(effects
				(font
					(size 1 1)
					(thickness 0.15)
				)
			)
		)
		(property "License" "Apache-2.0"
			(at 100.99 233.19 0)
			(layer "F.Fab")
			(hide yes)
			(effects
				(font
					(size 1 1)
					(thickness 0.15)
				)
			)
		)
		(property "MPN" ""
			(at 100.99 233.19 0)
			(layer "F.Fab")
			(hide yes)
			(effects
				(font
					(size 1 1)
					(thickness 0.15)
				)
			)
		)
		(property "Manufacturer" ""
			(at 100.99 233.19 0)
			(layer "F.Fab")
			(hide yes)
			(effects
				(font
					(size 1 1)
					(thickness 0.15)
				)
			)
		)
		(sheetname "/Power Supply/")
		(sheetfile "supply.kicad_sch")
		(attr exclude_from_pos_files)
		(fp_circle
			(center 0 0)
			(end 0.475 0)
			(stroke
				(width 0.05)
				(type default)
			)
			(fill no)
			(layer "F.CrtYd")
		)
		(fp_text user "${REFERENCE}"
			(at -0.4 2.7 270)
			(layer "F.Fab")
			(effects
				(font
					(size 0.7 0.7)
					(thickness 0.15)
				)
				(justify left bottom)
			)
		)
		(fp_text user "Author: Antmicro"
			(at -0.4 3.901 270)
			(layer "F.Fab")
			(effects
				(font
					(size 0.7 0.7)
					(thickness 0.15)
				)
				(justify left bottom)
			)
		)
		(fp_text user "License: Apache-2.0"
			(at -0.4 5.101 270)
			(layer "F.Fab")
			(effects
				(font
					(size 0.7 0.7)
					(thickness 0.15)
				)
				(justify left bottom)
			)
		)
		(pad "1" smd circle
			(at 0 0 270)
			(size 0.75 0.75)
			(layers "F.Cu" "F.Mask")
			(net 375 "Net-(U7-EN)")
			(pinfunction "1")
			(pintype "passive")
		)
	)
)
